(kicad_pcb
	(version 20260206)
	(generator "pcbnew")
	(generator_version "10.0")
	(general
		(thickness 1.6)
		(legacy_teardrops no)
	)
	(paper "A4")
	(title_block
		(title "baseboard — 13948-1b.1110WZS1818.brd")
		(comment 1 "Honey Badger (Wiwynn) / footprint 1078 of 2523 (SU1), pads 1-115 of 672")
	)
	(layers
		(0 "F.Cu" signal "TOP")
		(4 "In1.Cu" signal "L2GND")
		(6 "In2.Cu" signal "L3")
		(8 "In3.Cu" signal "L4VCC")
		(10 "In4.Cu" signal "L5VCC")
		(12 "In5.Cu" signal "L6")
		(14 "In6.Cu" signal "L7GND")
		(2 "B.Cu" signal "BOTTOM")
		(9 "F.Adhes" user "F.Adhesive")
		(11 "B.Adhes" user "B.Adhesive")
		(13 "F.Paste" user "Package Geometry/Pastemask Top")
		(15 "B.Paste" user "Package Geometry/Pastemask Bottom")
		(5 "F.SilkS" user "Ref Des/Silkscreen Top")
		(7 "B.SilkS" user "Ref Des/Silkscreen Bottom")
		(1 "F.Mask" user "Board Geometry/Soldermask Top")
		(3 "B.Mask" user "Board Geometry/Soldermask Bottom")
		(17 "Dwgs.User" user "User.Drawings")
		(19 "Cmts.User" user "User.Comments")
		(21 "Eco1.User" user "User.Eco1")
		(23 "Eco2.User" user "User.Eco2")
		(25 "Edge.Cuts" user "Board Geometry/Outline")
		(27 "Margin" user)
		(31 "F.CrtYd" user "Package Geometry/Place Bound Top")
		(29 "B.CrtYd" user "Package Geometry/Place Bound Bottom")
		(35 "F.Fab" user "Ref Des/Assembly Top")
		(33 "B.Fab" user "Ref Des/Assembly Bottom")
	)
	(footprint ""
		(layer "F.Cu")
		(at 114.84991 -94.84995 90)
		(property "Reference" "SU1"
			(at 0 0 90)
			(layer "F.SilkS")
			(hide yes)
			(effects
				(font
					(size 1.27 1.27)
				)
			)
		)
		(property "Value" "SAS3X24RLC1-DB-500021106-GP"
			(at -21.4503 -7.4168 90)
			(unlocked yes)
			(layer "F.Fab")
			(hide yes)
			(effects
				(font
					(size 1.016 1.016)
					(thickness 0.1524)
				)
			)
		)
		(property "Device Type" "BGA672C27H83"
			(at -21.4503 -8.9408 90)
			(unlocked yes)
			(layer "F.Fab")
			(hide yes)
			(effects
				(font
					(size 1.016 1.016)
					(thickness 0.1524)
				)
			)
		)
		(duplicate_pad_numbers_are_jumpers no)
		(pad "A2" smd circle
			(at -11.500104 -12.500102 90)
			(size 0.508 0.508)
			(layers "F.Cu" "F.Mask" "F.Paste")
			(net "RESET_N")
		)
		(pad "A3" smd circle
			(at -10.500106 -12.500102 90)
			(size 0.508 0.508)
			(layers "F.Cu" "F.Mask" "F.Paste")
			(net "Net_1126")
		)
		(pad "A4" smd circle
			(at -9.500108 -12.500102 90)
			(size 0.4572 0.4572)
			(layers "F.Cu" "F.Mask" "F.Paste")
			(net "EXP_XM_OE_N")
		)
		(pad "A5" smd circle
			(at -8.50011 -12.500102 90)
			(size 0.4572 0.4572)
			(layers "F.Cu" "F.Mask" "F.Paste")
			(net "XM_DATA8")
		)
		(pad "A6" smd circle
			(at -7.500112 -12.500102 90)
			(size 0.4572 0.4572)
			(layers "F.Cu" "F.Mask" "F.Paste")
			(net "XM_DATA6")
		)
		(pad "A7" smd circle
			(at -6.500114 -12.500102 90)
			(size 0.4572 0.4572)
			(layers "F.Cu" "F.Mask" "F.Paste")
			(net "XM_DATA14")
		)
		(pad "A8" smd circle
			(at -5.500116 -12.500102 90)
			(size 0.4572 0.4572)
			(layers "F.Cu" "F.Mask" "F.Paste")
			(net "XM_DATA1")
		)
		(pad "A9" smd circle
			(at -4.500118 -12.500102 90)
			(size 0.4572 0.4572)
			(layers "F.Cu" "F.Mask" "F.Paste")
			(net "EXP_XM_BUSY_N")
		)
		(pad "A10" smd circle
			(at -3.50012 -12.500102 90)
			(size 0.4572 0.4572)
			(layers "F.Cu" "F.Mask" "F.Paste")
			(net "EXP_XM_ADDR_7")
		)
		(pad "A11" smd circle
			(at -2.500122 -12.500102 90)
			(size 0.4572 0.4572)
			(layers "F.Cu" "F.Mask" "F.Paste")
			(net "EXP_XM_ADDR_3")
		)
		(pad "A12" smd circle
			(at -1.500124 -12.500102 90)
			(size 0.4572 0.4572)
			(layers "F.Cu" "F.Mask" "F.Paste")
			(net "EXP_XM_ADDR_20")
		)
		(pad "A13" smd circle
			(at -0.500126 -12.500102 90)
			(size 0.4572 0.4572)
			(layers "F.Cu" "F.Mask" "F.Paste")
			(net "EXP_XM_ADDR_21")
		)
		(pad "A14" smd circle
			(at 0.500126 -12.500102 90)
			(size 0.4572 0.4572)
			(layers "F.Cu" "F.Mask" "F.Paste")
			(net "EXP_XM_ADDR_14")
		)
		(pad "A15" smd circle
			(at 1.500124 -12.500102 90)
			(size 0.4572 0.4572)
			(layers "F.Cu" "F.Mask" "F.Paste")
			(net "EXP_XM_ADDR_12")
		)
		(pad "A16" smd circle
			(at 2.500122 -12.500102 90)
			(size 0.4572 0.4572)
			(layers "F.Cu" "F.Mask" "F.Paste")
			(net "EXP_PWM_OUT1")
		)
		(pad "A17" smd circle
			(at 3.50012 -12.500102 90)
			(size 0.4572 0.4572)
			(layers "F.Cu" "F.Mask" "F.Paste")
			(net "EXP_FW_DET_BOARD_VER_2")
		)
		(pad "A18" smd circle
			(at 4.500118 -12.500102 90)
			(size 0.4572 0.4572)
			(layers "F.Cu" "F.Mask" "F.Paste")
			(net "EXP_FW_DET_BOARD_VER_0")
		)
		(pad "A19" smd circle
			(at 5.500116 -12.500102 90)
			(size 0.4572 0.4572)
			(layers "F.Cu" "F.Mask" "F.Paste")
			(net "EXP_GPIO_11")
		)
		(pad "A20" smd circle
			(at 6.500114 -12.500102 90)
			(size 0.4572 0.4572)
			(layers "F.Cu" "F.Mask" "F.Paste")
			(net "EXP_GPIO_6")
		)
		(pad "A21" smd circle
			(at 7.500112 -12.500102 90)
			(size 0.4572 0.4572)
			(layers "F.Cu" "F.Mask" "F.Paste")
			(net "EXP_GPIO_0")
		)
		(pad "A22" smd circle
			(at 8.50011 -12.500102 90)
			(size 0.4572 0.4572)
			(layers "F.Cu" "F.Mask" "F.Paste")
			(net "SDB_R_TX")
		)
		(pad "A23" smd circle
			(at 9.500108 -12.500102 90)
			(size 0.4572 0.4572)
			(layers "F.Cu" "F.Mask" "F.Paste")
			(net "UART_RTS")
		)
		(pad "A24" smd circle
			(at 10.500106 -12.500102 90)
			(size 0.508 0.508)
			(layers "F.Cu" "F.Mask" "F.Paste")
			(net "SIO_D_OUT")
		)
		(pad "A25" smd circle
			(at 11.500104 -12.500102 90)
			(size 0.508 0.508)
			(layers "F.Cu" "F.Mask" "F.Paste")
			(net "EXP_I2C_SCL_4")
		)
		(pad "AA1" smd circle
			(at -12.500102 7.500112 90)
			(size 0.4572 0.4572)
			(layers "F.Cu" "F.Mask" "F.Paste")
			(net "GND")
		)
		(pad "AA2" smd circle
			(at -11.500104 7.500112 90)
			(size 0.4572 0.4572)
			(layers "F.Cu" "F.Mask" "F.Paste")
			(net "SAS3008_RAID_TX_N1")
		)
		(pad "AA3" smd circle
			(at -10.500106 7.500112 90)
			(size 0.4572 0.4572)
			(layers "F.Cu" "F.Mask" "F.Paste")
			(net "SAS3008_RAID_TX_N2")
		)
		(pad "AA4" smd circle
			(at -9.500108 7.500112 90)
			(size 0.4572 0.4572)
			(layers "F.Cu" "F.Mask" "F.Paste")
			(net "SAS3008_RAID_TX_N3")
		)
		(pad "AA5" smd circle
			(at -8.50011 7.500112 90)
			(size 0.4572 0.4572)
			(layers "F.Cu" "F.Mask" "F.Paste")
			(net "SAS_EXP2CONN_RX_N_20")
		)
		(pad "AA6" smd circle
			(at -7.500112 7.500112 90)
			(size 0.4572 0.4572)
			(layers "F.Cu" "F.Mask" "F.Paste")
			(net "SAS_EXP2CONN_RX_N_21")
		)
		(pad "AA7" smd circle
			(at -6.500114 7.500112 90)
			(size 0.4572 0.4572)
			(layers "F.Cu" "F.Mask" "F.Paste")
			(net "SAS_EXP2CONN_RX_N_22")
		)
		(pad "AA8" smd circle
			(at -5.500116 7.500112 90)
			(size 0.4572 0.4572)
			(layers "F.Cu" "F.Mask" "F.Paste")
			(net "SAS_EXP2CONN_RX_N_23")
		)
		(pad "AA9" smd circle
			(at -4.500118 7.500112 90)
			(size 0.4572 0.4572)
			(layers "F.Cu" "F.Mask" "F.Paste")
			(net "SAS_GF_EXP_RX_DN0")
		)
		(pad "AA10" smd circle
			(at -3.50012 7.500112 90)
			(size 0.4572 0.4572)
			(layers "F.Cu" "F.Mask" "F.Paste")
			(net "SAS_GF_EXP_RX_DN1")
		)
		(pad "AA11" smd circle
			(at -2.500122 7.500112 90)
			(size 0.4572 0.4572)
			(layers "F.Cu" "F.Mask" "F.Paste")
			(net "SAS_GF_EXP_RX_DN2")
		)
		(pad "AA12" smd circle
			(at -1.500124 7.500112 90)
			(size 0.4572 0.4572)
			(layers "F.Cu" "F.Mask" "F.Paste")
			(net "SAS_GF_EXP_RX_DN3")
		)
		(pad "AA13" smd circle
			(at -0.500126 7.500112 90)
			(size 0.4572 0.4572)
			(layers "F.Cu" "F.Mask" "F.Paste")
			(net "Net_1125")
		)
		(pad "AA14" smd circle
			(at 0.500126 7.500112 90)
			(size 0.4572 0.4572)
			(layers "F.Cu" "F.Mask" "F.Paste")
			(net "Net_1124")
		)
		(pad "AA15" smd circle
			(at 1.500124 7.500112 90)
			(size 0.4572 0.4572)
			(layers "F.Cu" "F.Mask" "F.Paste")
			(net "Net_1123")
		)
		(pad "AA16" smd circle
			(at 2.500122 7.500112 90)
			(size 0.4572 0.4572)
			(layers "F.Cu" "F.Mask" "F.Paste")
			(net "Net_1122")
		)
		(pad "AA17" smd circle
			(at 3.50012 7.500112 90)
			(size 0.4572 0.4572)
			(layers "F.Cu" "F.Mask" "F.Paste")
			(net "Net_1121")
		)
		(pad "AA18" smd circle
			(at 4.500118 7.500112 90)
			(size 0.4572 0.4572)
			(layers "F.Cu" "F.Mask" "F.Paste")
			(net "Net_1104")
		)
		(pad "AA19" smd circle
			(at 5.500116 7.500112 90)
			(size 0.4572 0.4572)
			(layers "F.Cu" "F.Mask" "F.Paste")
			(net "Net_1103")
		)
		(pad "AA20" smd circle
			(at 6.500114 7.500112 90)
			(size 0.4572 0.4572)
			(layers "F.Cu" "F.Mask" "F.Paste")
			(net "Net_1102")
		)
		(pad "AA21" smd circle
			(at 7.500112 7.500112 90)
			(size 0.4572 0.4572)
			(layers "F.Cu" "F.Mask" "F.Paste")
			(net "GB_VDDA")
		)
		(pad "AA22" smd circle
			(at 8.50011 7.500112 90)
			(size 0.4572 0.4572)
			(layers "F.Cu" "F.Mask" "F.Paste")
			(net "GND")
		)
		(pad "AA23" smd circle
			(at 9.500108 7.500112 90)
			(size 0.4572 0.4572)
			(layers "F.Cu" "F.Mask" "F.Paste")
			(net "GB_VDDA")
		)
		(pad "AA24" smd circle
			(at 10.500106 7.500112 90)
			(size 0.4572 0.4572)
			(layers "F.Cu" "F.Mask" "F.Paste")
			(net "Net_1101")
		)
		(pad "AA25" smd circle
			(at 11.500104 7.500112 90)
			(size 0.4572 0.4572)
			(layers "F.Cu" "F.Mask" "F.Paste")
			(net "Net_1100")
		)
		(pad "AA26" smd circle
			(at 12.500102 7.500112 90)
			(size 0.4572 0.4572)
			(layers "F.Cu" "F.Mask" "F.Paste")
			(net "GND")
		)
		(pad "AB1" smd circle
			(at -12.500102 8.50011 90)
			(size 0.4572 0.4572)
			(layers "F.Cu" "F.Mask" "F.Paste")
			(net "SAS3008_RAID_TX_N0")
		)
		(pad "AB2" smd circle
			(at -11.500104 8.50011 90)
			(size 0.4572 0.4572)
			(layers "F.Cu" "F.Mask" "F.Paste")
			(net "SAS3008_RAID_TX_P1")
		)
		(pad "AB3" smd circle
			(at -10.500106 8.50011 90)
			(size 0.4572 0.4572)
			(layers "F.Cu" "F.Mask" "F.Paste")
			(net "SAS3008_RAID_TX_P2")
		)
		(pad "AB4" smd circle
			(at -9.500108 8.50011 90)
			(size 0.4572 0.4572)
			(layers "F.Cu" "F.Mask" "F.Paste")
			(net "SAS3008_RAID_TX_P3")
		)
		(pad "AB5" smd circle
			(at -8.50011 8.50011 90)
			(size 0.4572 0.4572)
			(layers "F.Cu" "F.Mask" "F.Paste")
			(net "SAS_EXP2CONN_RX_P_20")
		)
		(pad "AB6" smd circle
			(at -7.500112 8.50011 90)
			(size 0.4572 0.4572)
			(layers "F.Cu" "F.Mask" "F.Paste")
			(net "SAS_EXP2CONN_RX_P_21")
		)
		(pad "AB7" smd circle
			(at -6.500114 8.50011 90)
			(size 0.4572 0.4572)
			(layers "F.Cu" "F.Mask" "F.Paste")
			(net "SAS_EXP2CONN_RX_P_22")
		)
		(pad "AB8" smd circle
			(at -5.500116 8.50011 90)
			(size 0.4572 0.4572)
			(layers "F.Cu" "F.Mask" "F.Paste")
			(net "SAS_EXP2CONN_RX_P_23")
		)
		(pad "AB9" smd circle
			(at -4.500118 8.50011 90)
			(size 0.4572 0.4572)
			(layers "F.Cu" "F.Mask" "F.Paste")
			(net "SAS_GF_EXP_RX_DP0")
		)
		(pad "AB10" smd circle
			(at -3.50012 8.50011 90)
			(size 0.4572 0.4572)
			(layers "F.Cu" "F.Mask" "F.Paste")
			(net "SAS_GF_EXP_RX_DP1")
		)
		(pad "AB11" smd circle
			(at -2.500122 8.50011 90)
			(size 0.4572 0.4572)
			(layers "F.Cu" "F.Mask" "F.Paste")
			(net "SAS_GF_EXP_RX_DP2")
		)
		(pad "AB12" smd circle
			(at -1.500124 8.50011 90)
			(size 0.4572 0.4572)
			(layers "F.Cu" "F.Mask" "F.Paste")
			(net "SAS_GF_EXP_RX_DP3")
		)
		(pad "AB13" smd circle
			(at -0.500126 8.50011 90)
			(size 0.4572 0.4572)
			(layers "F.Cu" "F.Mask" "F.Paste")
			(net "Net_1120")
		)
		(pad "AB14" smd circle
			(at 0.500126 8.50011 90)
			(size 0.4572 0.4572)
			(layers "F.Cu" "F.Mask" "F.Paste")
			(net "Net_1119")
		)
		(pad "AB15" smd circle
			(at 1.500124 8.50011 90)
			(size 0.4572 0.4572)
			(layers "F.Cu" "F.Mask" "F.Paste")
			(net "Net_1118")
		)
		(pad "AB16" smd circle
			(at 2.500122 8.50011 90)
			(size 0.4572 0.4572)
			(layers "F.Cu" "F.Mask" "F.Paste")
			(net "Net_1117")
		)
		(pad "AB17" smd circle
			(at 3.50012 8.50011 90)
			(size 0.4572 0.4572)
			(layers "F.Cu" "F.Mask" "F.Paste")
			(net "Net_1116")
		)
		(pad "AB18" smd circle
			(at 4.500118 8.50011 90)
			(size 0.4572 0.4572)
			(layers "F.Cu" "F.Mask" "F.Paste")
			(net "Net_1099")
		)
		(pad "AB19" smd circle
			(at 5.500116 8.50011 90)
			(size 0.4572 0.4572)
			(layers "F.Cu" "F.Mask" "F.Paste")
			(net "Net_1098")
		)
		(pad "AB20" smd circle
			(at 6.500114 8.50011 90)
			(size 0.4572 0.4572)
			(layers "F.Cu" "F.Mask" "F.Paste")
			(net "Net_1097")
		)
		(pad "AB21" smd circle
			(at 7.500112 8.50011 90)
			(size 0.4572 0.4572)
			(layers "F.Cu" "F.Mask" "F.Paste")
			(net "GND")
		)
		(pad "AB22" smd circle
			(at 8.50011 8.50011 90)
			(size 0.4572 0.4572)
			(layers "F.Cu" "F.Mask" "F.Paste")
			(net "Net_1096")
		)
		(pad "AB23" smd circle
			(at 9.500108 8.50011 90)
			(size 0.4572 0.4572)
			(layers "F.Cu" "F.Mask" "F.Paste")
			(net "Net_1095")
		)
		(pad "AB24" smd circle
			(at 10.500106 8.50011 90)
			(size 0.4572 0.4572)
			(layers "F.Cu" "F.Mask" "F.Paste")
			(net "GND")
		)
		(pad "AB25" smd circle
			(at 11.500104 8.50011 90)
			(size 0.4572 0.4572)
			(layers "F.Cu" "F.Mask" "F.Paste")
			(net "GB_VDDA")
		)
		(pad "AB26" smd circle
			(at 12.500102 8.50011 90)
			(size 0.4572 0.4572)
			(layers "F.Cu" "F.Mask" "F.Paste")
			(net "GND")
		)
		(pad "AC1" smd circle
			(at -12.500102 9.500108 90)
			(size 0.4572 0.4572)
			(layers "F.Cu" "F.Mask" "F.Paste")
			(net "SAS3008_RAID_TX_P0")
		)
		(pad "AC2" smd circle
			(at -11.500104 9.500108 90)
			(size 0.4572 0.4572)
			(layers "F.Cu" "F.Mask" "F.Paste")
			(net "GND")
		)
		(pad "AC3" smd circle
			(at -10.500106 9.500108 90)
			(size 0.4572 0.4572)
			(layers "F.Cu" "F.Mask" "F.Paste")
			(net "GB_VDDA")
		)
		(pad "AC4" smd circle
			(at -9.500108 9.500108 90)
			(size 0.4572 0.4572)
			(layers "F.Cu" "F.Mask" "F.Paste")
			(net "GND")
		)
		(pad "AC5" smd circle
			(at -8.50011 9.500108 90)
			(size 0.4572 0.4572)
			(layers "F.Cu" "F.Mask" "F.Paste")
			(net "GB_VDDA")
		)
		(pad "AC6" smd circle
			(at -7.500112 9.500108 90)
			(size 0.4572 0.4572)
			(layers "F.Cu" "F.Mask" "F.Paste")
			(net "GND")
		)
		(pad "AC7" smd circle
			(at -6.500114 9.500108 90)
			(size 0.4572 0.4572)
			(layers "F.Cu" "F.Mask" "F.Paste")
			(net "GB_VDDA")
		)
		(pad "AC8" smd circle
			(at -5.500116 9.500108 90)
			(size 0.4572 0.4572)
			(layers "F.Cu" "F.Mask" "F.Paste")
			(net "GND")
		)
		(pad "AC9" smd circle
			(at -4.500118 9.500108 90)
			(size 0.4572 0.4572)
			(layers "F.Cu" "F.Mask" "F.Paste")
			(net "GB_VDDA")
		)
		(pad "AC10" smd circle
			(at -3.50012 9.500108 90)
			(size 0.4572 0.4572)
			(layers "F.Cu" "F.Mask" "F.Paste")
			(net "GND")
		)
		(pad "AC11" smd circle
			(at -2.500122 9.500108 90)
			(size 0.4572 0.4572)
			(layers "F.Cu" "F.Mask" "F.Paste")
			(net "GB_VDDA")
		)
		(pad "AC12" smd circle
			(at -1.500124 9.500108 90)
			(size 0.4572 0.4572)
			(layers "F.Cu" "F.Mask" "F.Paste")
			(net "GND")
		)
		(pad "AC13" smd circle
			(at -0.500126 9.500108 90)
			(size 0.4572 0.4572)
			(layers "F.Cu" "F.Mask" "F.Paste")
			(net "GB_VDDA")
		)
		(pad "AC14" smd circle
			(at 0.500126 9.500108 90)
			(size 0.4572 0.4572)
			(layers "F.Cu" "F.Mask" "F.Paste")
			(net "GND")
		)
		(pad "AC15" smd circle
			(at 1.500124 9.500108 90)
			(size 0.4572 0.4572)
			(layers "F.Cu" "F.Mask" "F.Paste")
			(net "GB_VDDA")
		)
		(pad "AC16" smd circle
			(at 2.500122 9.500108 90)
			(size 0.4572 0.4572)
			(layers "F.Cu" "F.Mask" "F.Paste")
			(net "GND")
		)
		(pad "AC17" smd circle
			(at 3.50012 9.500108 90)
			(size 0.4572 0.4572)
			(layers "F.Cu" "F.Mask" "F.Paste")
			(net "GB_VDDA")
		)
		(pad "AC18" smd circle
			(at 4.500118 9.500108 90)
			(size 0.4572 0.4572)
			(layers "F.Cu" "F.Mask" "F.Paste")
			(net "GND")
		)
		(pad "AC19" smd circle
			(at 5.500116 9.500108 90)
			(size 0.4572 0.4572)
			(layers "F.Cu" "F.Mask" "F.Paste")
			(net "GB_VDDA")
		)
		(pad "AC20" smd circle
			(at 6.500114 9.500108 90)
			(size 0.4572 0.4572)
			(layers "F.Cu" "F.Mask" "F.Paste")
			(net "GND")
		)
		(pad "AC21" smd circle
			(at 7.500112 9.500108 90)
			(size 0.4572 0.4572)
			(layers "F.Cu" "F.Mask" "F.Paste")
			(net "GB_VDDA")
		)
		(pad "AC22" smd circle
			(at 8.50011 9.500108 90)
			(size 0.4572 0.4572)
			(layers "F.Cu" "F.Mask" "F.Paste")
			(net "GND")
		)
		(pad "AC23" smd circle
			(at 9.500108 9.500108 90)
			(size 0.4572 0.4572)
			(layers "F.Cu" "F.Mask" "F.Paste")
			(net "GB_VDDA")
		)
		(pad "AC24" smd circle
			(at 10.500106 9.500108 90)
			(size 0.4572 0.4572)
			(layers "F.Cu" "F.Mask" "F.Paste")
			(net "GND")
		)
		(pad "AC25" smd circle
			(at 11.500104 9.500108 90)
			(size 0.4572 0.4572)
			(layers "F.Cu" "F.Mask" "F.Paste")
			(net "GND")
		)
		(pad "AC26" smd circle
			(at 12.500102 9.500108 90)
			(size 0.4572 0.4572)
			(layers "F.Cu" "F.Mask" "F.Paste")
			(net "GND")
		)
		(pad "AD1" smd circle
			(at -12.500102 10.500106 90)
			(size 0.508 0.508)
			(layers "F.Cu" "F.Mask" "F.Paste")
			(net "GND")
		)
		(pad "AD2" smd circle
			(at -11.500104 10.500106 90)
			(size 0.508 0.508)
			(layers "F.Cu" "F.Mask" "F.Paste")
			(net "GB_VDDA")
		)
		(pad "AD3" smd circle
			(at -10.500106 10.500106 90)
			(size 0.508 0.508)
			(layers "F.Cu" "F.Mask" "F.Paste")
			(net "SAS_HDD_TX13_N")
		)
		(pad "AD4" smd circle
			(at -9.500108 10.500106 90)
			(size 0.4572 0.4572)
			(layers "F.Cu" "F.Mask" "F.Paste")
			(net "GB_VDDA")
		)
		(pad "AD5" smd circle
			(at -8.50011 10.500106 90)
			(size 0.4572 0.4572)
			(layers "F.Cu" "F.Mask" "F.Paste")
			(net "SAS_HDD_TX15_N")
		)
		(pad "AD6" smd circle
			(at -7.500112 10.500106 90)
			(size 0.4572 0.4572)
			(layers "F.Cu" "F.Mask" "F.Paste")
			(net "GB_VDDA")
		)
		(pad "AD7" smd circle
			(at -6.500114 10.500106 90)
			(size 0.4572 0.4572)
			(layers "F.Cu" "F.Mask" "F.Paste")
			(net "3X24_SAS_TX17_N")
		)
		(pad "AD8" smd circle
			(at -5.500116 10.500106 90)
			(size 0.4572 0.4572)
			(layers "F.Cu" "F.Mask" "F.Paste")
			(net "GB_VDDA")
		)
		(pad "AD9" smd circle
			(at -4.500118 10.500106 90)
			(size 0.4572 0.4572)
			(layers "F.Cu" "F.Mask" "F.Paste")
			(net "3X24_SAS_TX19_N")
		)
		(pad "AD10" smd circle
			(at -3.50012 10.500106 90)
			(size 0.4572 0.4572)
			(layers "F.Cu" "F.Mask" "F.Paste")
			(net "GB_VDDA")
		)
		(pad "AD11" smd circle
			(at -2.500122 10.500106 90)
			(size 0.4572 0.4572)
			(layers "F.Cu" "F.Mask" "F.Paste")
			(net "3X24_SAS_TX21_N")
		)
		(pad "AD12" smd circle
			(at -1.500124 10.500106 90)
			(size 0.4572 0.4572)
			(layers "F.Cu" "F.Mask" "F.Paste")
			(net "GB_VDDA")
		)
		(pad "AD13" smd circle
			(at -0.500126 10.500106 90)
			(size 0.4572 0.4572)
			(layers "F.Cu" "F.Mask" "F.Paste")
			(net "3X24_SAS_TX23_N")
		)
	)
)
